# T6G (Grand Teton) — schematic netlist excerpt (pin names and nets, part order shuffled) for the footprints in the layout excerpt that follows; sources: Cadence DE-HDL packaged netlist, KiCad conversion of 04192023_DAF0TMB3IC0_F0TG_MB_C_brd_V02_OCP.brd

R8085  Q_RES  10K 1% EMPTY  pkg 0402LF  page 92 : A = P3V3_AUX ; B = PWRGD_CHGL_CPU0_R1
R863  Q_RES  1K 1% EMPTY  pkg 0201LF  page 342 : A = RT_CPU1_P2_ADDR3 ; B = GND
PC2224  Q_CAP  220PF 50V 10% EMPTY  pkg 0402  page 264 : A = HSC_ON ; B = AGND_HSC

(kicad_pcb
	(version 20260206)
	(generator "pcbnew")
	(generator_version "10.0")
	(general
		(thickness 1.6)
		(legacy_teardrops no)
	)
	(paper "A4")
	(title_block
		(title "04192023_DAF0TMB3IC0_F0TG_MB_C_brd_V02_OCP.brd")
		(comment 1 "Grand Teton / footprints 693-695 of 8354")
	)
	(layers
		(0 "F.Cu" signal "TOP")
		(4 "In1.Cu" signal "GND")
		(6 "In2.Cu" signal "IN1")
		(8 "In3.Cu" signal "GND1")
		(10 "In4.Cu" signal "IN2")
		(12 "In5.Cu" signal "GND2")
		(14 "In6.Cu" signal "IN3")
		(16 "In7.Cu" signal "GND3")
		(18 "In8.Cu" signal "VCC")
		(20 "In9.Cu" signal "VCC1")
		(22 "In10.Cu" signal "GND4")
		(24 "In11.Cu" signal "IN4")
		(26 "In12.Cu" signal "GND5")
		(28 "In13.Cu" signal "IN5")
		(30 "In14.Cu" signal "GND6")
		(32 "In15.Cu" signal "IN6")
		(34 "In16.Cu" signal "GND7")
		(2 "B.Cu" signal "BOTTOM")
		(9 "F.Adhes" user "F.Adhesive")
		(11 "B.Adhes" user "B.Adhesive")
		(13 "F.Paste" user "Package Geometry/Pastemask Top")
		(15 "B.Paste" user "Package Geometry/Pastemask Bottom")
		(5 "F.SilkS" user "Ref Des/Silkscreen Top")
		(7 "B.SilkS" user "Ref Des/Silkscreen Bottom")
		(1 "F.Mask" user "Board Geometry/Soldermask Top")
		(3 "B.Mask" user "Board Geometry/Soldermask Bottom")
		(17 "Dwgs.User" user "User.Drawings")
		(19 "Cmts.User" user "User.Comments")
		(21 "Eco1.User" user "User.Eco1")
		(23 "Eco2.User" user "User.Eco2")
		(25 "Edge.Cuts" user "Board Geometry/Outline")
		(27 "Margin" user)
		(31 "F.CrtYd" user "Package Geometry/Place Bound Top")
		(29 "B.CrtYd" user "Package Geometry/Place Bound Bottom")
		(35 "F.Fab" user "Ref Des/Assembly Top")
		(33 "B.Fab" user "Ref Des/Assembly Bottom")
	)
	(footprint ""
		(layer "F.Cu")
		(at 203.2 -99.695)
		(property "Reference" "R8085"
			(at 0 0 0)
			(layer "F.SilkS")
			(hide yes)
			(effects
				(font
					(size 1.27 1.27)
				)
			)
		)
		(property "Value" ""
			(at 0 0 0)
			(layer "F.Fab")
			(effects
				(font
					(size 1.27 1.27)
				)
			)
		)
		(duplicate_pad_numbers_are_jumpers no)
		(fp_line
			(start -0.7874 -0.4064)
			(end 0.7874 -0.4064)
			(stroke
				(width 0.1524)
				(type default)
			)
			(layer "F.SilkS")
		)
		(fp_line
			(start -0.7874 0.4064)
			(end -0.7874 -0.4064)
			(stroke
				(width 0.1524)
				(type default)
			)
			(layer "F.SilkS")
		)
		(fp_line
			(start 0.7874 -0.4064)
			(end 0.7874 0.4064)
			(stroke
				(width 0.1524)
				(type default)
			)
			(layer "F.SilkS")
		)
		(fp_line
			(start 0.7874 0.4064)
			(end -0.7874 0.4064)
			(stroke
				(width 0.1524)
				(type default)
			)
			(layer "F.SilkS")
		)
		(fp_line
			(start -0.67945 -0.305054)
			(end -0.12065 -0.305054)
			(stroke
				(width 0.1)
				(type default)
			)
			(layer "F.Fab")
		)
		(fp_line
			(start -0.67945 0.3048)
			(end -0.67945 -0.305054)
			(stroke
				(width 0.1)
				(type default)
			)
			(layer "F.Fab")
		)
		(fp_line
			(start -0.12065 -0.305054)
			(end -0.12065 -0.2794)
			(stroke
				(width 0.1)
				(type default)
			)
			(layer "F.Fab")
		)
		(fp_line
			(start -0.12065 -0.2794)
			(end 0.12065 -0.2794)
			(stroke
				(width 0.1)
				(type default)
			)
			(layer "F.Fab")
		)
		(fp_line
			(start -0.12065 0.2794)
			(end -0.12065 0.3048)
			(stroke
				(width 0.1)
				(type default)
			)
			(layer "F.Fab")
		)
		(fp_line
			(start -0.12065 0.3048)
			(end -0.67945 0.3048)
			(stroke
				(width 0.1)
				(type default)
			)
			(layer "F.Fab")
		)
		(fp_line
			(start 0.120396 0.2794)
			(end -0.12065 0.2794)
			(stroke
				(width 0.1)
				(type default)
			)
			(layer "F.Fab")
		)
		(fp_line
			(start 0.120396 0.3048)
			(end 0.120396 0.2794)
			(stroke
				(width 0.1)
				(type default)
			)
			(layer "F.Fab")
		)
		(fp_line
			(start 0.12065 -0.3048)
			(end 0.67945 -0.3048)
			(stroke
				(width 0.1)
				(type default)
			)
			(layer "F.Fab")
		)
		(fp_line
			(start 0.12065 -0.2794)
			(end 0.12065 -0.3048)
			(stroke
				(width 0.1)
				(type default)
			)
			(layer "F.Fab")
		)
		(fp_line
			(start 0.67945 -0.3048)
			(end 0.67945 0.3048)
			(stroke
				(width 0.1)
				(type default)
			)
			(layer "F.Fab")
		)
		(fp_line
			(start 0.67945 0.3048)
			(end 0.120396 0.3048)
			(stroke
				(width 0.1)
				(type default)
			)
			(layer "F.Fab")
		)
		(pad "1" smd circle
			(at -0.40005 0)
			(size 0 0)
			(layers "F.Cu" "F.Mask" "F.Paste")
			(net "P3V3_AUX")
		)
		(pad "2" smd circle
			(at 0.40005 0)
			(size 0 0)
			(layers "F.Cu" "F.Mask" "F.Paste")
			(net "PWRGD_CHGL_CPU0_R1")
		)
	)
	(footprint ""
		(layer "F.Cu")
		(at 226.0981 -404.020782)
		(property "Reference" "PC2224"
			(at 0 0 0)
			(layer "F.SilkS")
			(hide yes)
			(effects
				(font
					(size 1.27 1.27)
				)
			)
		)
		(property "Value" ""
			(at 0 0 0)
			(layer "F.Fab")
			(effects
				(font
					(size 1.27 1.27)
				)
			)
		)
		(duplicate_pad_numbers_are_jumpers no)
		(fp_line
			(start -0.7874 -0.4064)
			(end 0.7874 -0.4064)
			(stroke
				(width 0.1524)
				(type default)
			)
			(layer "F.SilkS")
		)
		(fp_line
			(start -0.7874 0.4064)
			(end -0.7874 -0.4064)
			(stroke
				(width 0.1524)
				(type default)
			)
			(layer "F.SilkS")
		)
		(fp_line
			(start 0.7874 -0.4064)
			(end 0.7874 0.4064)
			(stroke
				(width 0.1524)
				(type default)
			)
			(layer "F.SilkS")
		)
		(fp_line
			(start 0.7874 0.4064)
			(end -0.7874 0.4064)
			(stroke
				(width 0.1524)
				(type default)
			)
			(layer "F.SilkS")
		)
		(fp_line
			(start -0.67945 -0.305054)
			(end -0.12065 -0.305054)
			(stroke
				(width 0.1)
				(type default)
			)
			(layer "F.Fab")
		)
		(fp_line
			(start -0.67945 0.3048)
			(end -0.67945 -0.305054)
			(stroke
				(width 0.1)
				(type default)
			)
			(layer "F.Fab")
		)
		(fp_line
			(start -0.12065 -0.305054)
			(end -0.12065 -0.2794)
			(stroke
				(width 0.1)
				(type default)
			)
			(layer "F.Fab")
		)
		(fp_line
			(start -0.12065 -0.2794)
			(end 0.12065 -0.2794)
			(stroke
				(width 0.1)
				(type default)
			)
			(layer "F.Fab")
		)
		(fp_line
			(start -0.12065 0.2794)
			(end -0.12065 0.3048)
			(stroke
				(width 0.1)
				(type default)
			)
			(layer "F.Fab")
		)
		(fp_line
			(start -0.12065 0.3048)
			(end -0.67945 0.3048)
			(stroke
				(width 0.1)
				(type default)
			)
			(layer "F.Fab")
		)
		(fp_line
			(start 0.120396 0.2794)
			(end -0.12065 0.2794)
			(stroke
				(width 0.1)
				(type default)
			)
			(layer "F.Fab")
		)
		(fp_line
			(start 0.120396 0.3048)
			(end 0.120396 0.2794)
			(stroke
				(width 0.1)
				(type default)
			)
			(layer "F.Fab")
		)
		(fp_line
			(start 0.12065 -0.3048)
			(end 0.67945 -0.3048)
			(stroke
				(width 0.1)
				(type default)
			)
			(layer "F.Fab")
		)
		(fp_line
			(start 0.12065 -0.2794)
			(end 0.12065 -0.3048)
			(stroke
				(width 0.1)
				(type default)
			)
			(layer "F.Fab")
		)
		(fp_line
			(start 0.67945 -0.3048)
			(end 0.67945 0.3048)
			(stroke
				(width 0.1)
				(type default)
			)
			(layer "F.Fab")
		)
		(fp_line
			(start 0.67945 0.3048)
			(end 0.120396 0.3048)
			(stroke
				(width 0.1)
				(type default)
			)
			(layer "F.Fab")
		)
		(pad "1" smd circle
			(at -0.40005 0)
			(size 0 0)
			(layers "F.Cu" "F.Mask" "F.Paste")
			(net "HSC_ON")
		)
		(pad "2" smd circle
			(at 0.40005 0)
			(size 0 0)
			(layers "F.Cu" "F.Mask" "F.Paste")
			(net "AGND_HSC")
		)
	)
	(footprint ""
		(layer "F.Cu")
		(at 174.030894 -390.53008 180)
		(property "Reference" "R863"
			(at 0 0 180)
			(layer "F.SilkS")
			(hide yes)
			(effects
				(font
					(size 1.27 1.27)
				)
			)
		)
		(property "Value" ""
			(at 0 0 180)
			(layer "F.Fab")
			(effects
				(font
					(size 1.27 1.27)
				)
			)
		)
		(duplicate_pad_numbers_are_jumpers no)
		(fp_line
			(start 0.32512 0.175006)
			(end -0.32512 0.175006)
			(stroke
				(width 0.1)
				(type default)
			)
			(layer "F.Fab")
		)
		(fp_line
			(start 0.32512 -0.175006)
			(end 0.32512 0.175006)
			(stroke
				(width 0.1)
				(type default)
			)
			(layer "F.Fab")
		)
		(fp_line
			(start -0.32512 0.175006)
			(end -0.32512 -0.175006)
			(stroke
				(width 0.1)
				(type default)
			)
			(layer "F.Fab")
		)
		(fp_line
			(start -0.32512 -0.175006)
			(end 0.32512 -0.175006)
			(stroke
				(width 0.1)
				(type default)
			)
			(layer "F.Fab")
		)
		(pad "1" smd rect
			(at -0.2667 0 180)
			(size 0.3048 0.381)
			(layers "F.Cu" "F.Mask" "F.Paste")
			(net "RT_CPU1_P2_ADDR3")
		)
		(pad "2" smd rect
			(at 0.2667 0)
			(size 0.3048 0.381)
			(layers "F.Cu" "F.Mask" "F.Paste")
			(net "GND")
		)
	)
)
